# T6G (Grand Teton) — schematic netlist excerpt (pin names and nets, part order shuffled) for the footprints in the layout excerpt that follows; sources: Cadence DE-HDL packaged netlist, KiCad conversion of 04192023_DAF0TMB3IC0_F0TG_MB_C_brd_V02_OCP.brd

C904  Q_CAP_DIFFBUS  DIFF BUS_0.22UF 6.3V 20% X6S  pkg C0201  page 63 : \1\ = P5E_CPU0_P0_TX_C_DN<14> ; \2\ = P5E_CPU0_P0_TX_DN<14>
C6578  Q_CAP_DIFFBUS  DIFF BUS_0.22UF 6.3V 20% X6S  pkg C0201  page 297 : \1\ = P5E_CPU0_P2_TX_BUF_C_DN<6> ; \2\ = P5E_CPU0_P2_TX_BUF_DN<6>
R1049  Q_RES  1K 1% EMPTY  pkg 0402LF  page 169 : A = P12V_AUX_DSC_G1 ; B = GND

(kicad_pcb
	(version 20260206)
	(generator "pcbnew")
	(generator_version "10.0")
	(general
		(thickness 1.6)
		(legacy_teardrops no)
	)
	(paper "A4")
	(title_block
		(title "04192023_DAF0TMB3IC0_F0TG_MB_C_brd_V02_OCP.brd")
		(comment 1 "Grand Teton / footprints 3616-3618 of 8354")
	)
	(layers
		(0 "F.Cu" signal "TOP")
		(4 "In1.Cu" signal "GND")
		(6 "In2.Cu" signal "IN1")
		(8 "In3.Cu" signal "GND1")
		(10 "In4.Cu" signal "IN2")
		(12 "In5.Cu" signal "GND2")
		(14 "In6.Cu" signal "IN3")
		(16 "In7.Cu" signal "GND3")
		(18 "In8.Cu" signal "VCC")
		(20 "In9.Cu" signal "VCC1")
		(22 "In10.Cu" signal "GND4")
		(24 "In11.Cu" signal "IN4")
		(26 "In12.Cu" signal "GND5")
		(28 "In13.Cu" signal "IN5")
		(30 "In14.Cu" signal "GND6")
		(32 "In15.Cu" signal "IN6")
		(34 "In16.Cu" signal "GND7")
		(2 "B.Cu" signal "BOTTOM")
		(9 "F.Adhes" user "F.Adhesive")
		(11 "B.Adhes" user "B.Adhesive")
		(13 "F.Paste" user "Package Geometry/Pastemask Top")
		(15 "B.Paste" user "Package Geometry/Pastemask Bottom")
		(5 "F.SilkS" user "Ref Des/Silkscreen Top")
		(7 "B.SilkS" user "Ref Des/Silkscreen Bottom")
		(1 "F.Mask" user "Board Geometry/Soldermask Top")
		(3 "B.Mask" user "Board Geometry/Soldermask Bottom")
		(17 "Dwgs.User" user "User.Drawings")
		(19 "Cmts.User" user "User.Comments")
		(21 "Eco1.User" user "User.Eco1")
		(23 "Eco2.User" user "User.Eco2")
		(25 "Edge.Cuts" user "Board Geometry/Outline")
		(27 "Margin" user)
		(31 "F.CrtYd" user "Package Geometry/Place Bound Top")
		(29 "B.CrtYd" user "Package Geometry/Place Bound Bottom")
		(35 "F.Fab" user "Ref Des/Assembly Top")
		(33 "B.Fab" user "Ref Des/Assembly Bottom")
	)
	(footprint ""
		(layer "F.Cu")
		(at 36.73094 -108.09732 90)
		(property "Reference" "R1049"
			(at 0 0 90)
			(layer "F.SilkS")
			(hide yes)
			(effects
				(font
					(size 1.27 1.27)
				)
			)
		)
		(property "Value" ""
			(at 0 0 90)
			(layer "F.Fab")
			(effects
				(font
					(size 1.27 1.27)
				)
			)
		)
		(duplicate_pad_numbers_are_jumpers no)
		(fp_line
			(start 0.7874 -0.4064)
			(end 0.7874 0.4064)
			(stroke
				(width 0.1524)
				(type default)
			)
			(layer "F.SilkS")
		)
		(fp_line
			(start -0.7874 -0.4064)
			(end 0.7874 -0.4064)
			(stroke
				(width 0.1524)
				(type default)
			)
			(layer "F.SilkS")
		)
		(fp_line
			(start 0.7874 0.4064)
			(end -0.7874 0.4064)
			(stroke
				(width 0.1524)
				(type default)
			)
			(layer "F.SilkS")
		)
		(fp_line
			(start -0.7874 0.4064)
			(end -0.7874 -0.4064)
			(stroke
				(width 0.1524)
				(type default)
			)
			(layer "F.SilkS")
		)
		(fp_line
			(start -0.12065 -0.305054)
			(end -0.12065 -0.2794)
			(stroke
				(width 0.1)
				(type default)
			)
			(layer "F.Fab")
		)
		(fp_line
			(start -0.67945 -0.305054)
			(end -0.12065 -0.305054)
			(stroke
				(width 0.1)
				(type default)
			)
			(layer "F.Fab")
		)
		(fp_line
			(start 0.67945 -0.3048)
			(end 0.67945 0.3048)
			(stroke
				(width 0.1)
				(type default)
			)
			(layer "F.Fab")
		)
		(fp_line
			(start 0.12065 -0.3048)
			(end 0.67945 -0.3048)
			(stroke
				(width 0.1)
				(type default)
			)
			(layer "F.Fab")
		)
		(fp_line
			(start 0.12065 -0.2794)
			(end 0.12065 -0.3048)
			(stroke
				(width 0.1)
				(type default)
			)
			(layer "F.Fab")
		)
		(fp_line
			(start -0.12065 -0.2794)
			(end 0.12065 -0.2794)
			(stroke
				(width 0.1)
				(type default)
			)
			(layer "F.Fab")
		)
		(fp_line
			(start 0.120396 0.2794)
			(end -0.12065 0.2794)
			(stroke
				(width 0.1)
				(type default)
			)
			(layer "F.Fab")
		)
		(fp_line
			(start -0.12065 0.2794)
			(end -0.12065 0.3048)
			(stroke
				(width 0.1)
				(type default)
			)
			(layer "F.Fab")
		)
		(fp_line
			(start 0.67945 0.3048)
			(end 0.120396 0.3048)
			(stroke
				(width 0.1)
				(type default)
			)
			(layer "F.Fab")
		)
		(fp_line
			(start 0.120396 0.3048)
			(end 0.120396 0.2794)
			(stroke
				(width 0.1)
				(type default)
			)
			(layer "F.Fab")
		)
		(fp_line
			(start -0.12065 0.3048)
			(end -0.67945 0.3048)
			(stroke
				(width 0.1)
				(type default)
			)
			(layer "F.Fab")
		)
		(fp_line
			(start -0.67945 0.3048)
			(end -0.67945 -0.305054)
			(stroke
				(width 0.1)
				(type default)
			)
			(layer "F.Fab")
		)
		(pad "1" smd circle
			(at -0.40005 0 90)
			(size 0 0)
			(layers "F.Cu" "F.Mask" "F.Paste")
			(net "P12V_AUX_DSC_G1")
		)
		(pad "2" smd circle
			(at 0.40005 0 90)
			(size 0 0)
			(layers "F.Cu" "F.Mask" "F.Paste")
			(net "GND")
		)
	)
	(footprint ""
		(layer "F.Cu")
		(at 389.248142 -416.899344 -90)
		(property "Reference" "C6578"
			(at 0 0 270)
			(layer "F.SilkS")
			(hide yes)
			(effects
				(font
					(size 1.27 1.27)
				)
			)
		)
		(property "Value" ""
			(at 0 0 270)
			(layer "F.Fab")
			(effects
				(font
					(size 1.27 1.27)
				)
			)
		)
		(duplicate_pad_numbers_are_jumpers no)
		(fp_line
			(start -0.299974 0.150114)
			(end -0.299974 -0.150114)
			(stroke
				(width 0.1)
				(type default)
			)
			(layer "F.Fab")
		)
		(fp_line
			(start 0.299974 0.150114)
			(end -0.299974 0.150114)
			(stroke
				(width 0.1)
				(type default)
			)
			(layer "F.Fab")
		)
		(fp_line
			(start -0.299974 -0.150114)
			(end 0.299974 -0.150114)
			(stroke
				(width 0.1)
				(type default)
			)
			(layer "F.Fab")
		)
		(fp_line
			(start 0.299974 -0.150114)
			(end 0.299974 0.150114)
			(stroke
				(width 0.1)
				(type default)
			)
			(layer "F.Fab")
		)
		(pad "1" smd rect
			(at -0.2667 0 270)
			(size 0.3048 0.381)
			(layers "F.Cu" "F.Mask" "F.Paste")
			(net "P5E_CPU0_P2_TX_BUF_C_DN<6>")
		)
		(pad "2" smd rect
			(at 0.2667 0 270)
			(size 0.3048 0.381)
			(layers "F.Cu" "F.Mask" "F.Paste")
			(net "P5E_CPU0_P2_TX_BUF_DN<6>")
		)
	)
	(footprint ""
		(layer "F.Cu")
		(at 325.740776 -385.364228)
		(property "Reference" "C904"
			(at 0 0 0)
			(layer "F.SilkS")
			(hide yes)
			(effects
				(font
					(size 1.27 1.27)
				)
			)
		)
		(property "Value" ""
			(at 0 0 0)
			(layer "F.Fab")
			(effects
				(font
					(size 1.27 1.27)
				)
			)
		)
		(duplicate_pad_numbers_are_jumpers no)
		(fp_line
			(start -0.299974 -0.150114)
			(end 0.299974 -0.150114)
			(stroke
				(width 0.1)
				(type default)
			)
			(layer "F.Fab")
		)
		(fp_line
			(start -0.299974 0.150114)
			(end -0.299974 -0.150114)
			(stroke
				(width 0.1)
				(type default)
			)
			(layer "F.Fab")
		)
		(fp_line
			(start 0.299974 -0.150114)
			(end 0.299974 0.150114)
			(stroke
				(width 0.1)
				(type default)
			)
			(layer "F.Fab")
		)
		(fp_line
			(start 0.299974 0.150114)
			(end -0.299974 0.150114)
			(stroke
				(width 0.1)
				(type default)
			)
			(layer "F.Fab")
		)
		(pad "1" smd rect
			(at -0.2667 0)
			(size 0.3048 0.381)
			(layers "F.Cu" "F.Mask" "F.Paste")
			(net "P5E_CPU0_P0_TX_C_DN<14>")
		)
		(pad "2" smd rect
			(at 0.2667 0)
			(size 0.3048 0.381)
			(layers "F.Cu" "F.Mask" "F.Paste")
			(net "P5E_CPU0_P0_TX_DN<14>")
		)
	)
)
